(kicad_pcb
	(version 20260206)
	(generator "pcbnew")
	(generator_version "10.0")
	(general
		(thickness 1.6)
		(legacy_teardrops no)
	)
	(paper "A4")
	(title_block
		(title "01162023_DA0F0TEBIF0_F0T_Expander_BD_F_brd_V02_OCP.brd")
		(comment 1 "Grand Teton / footprints 4162-4168 of 9728")
	)
	(layers
		(0 "F.Cu" signal "TOP")
		(4 "In1.Cu" signal "GND")
		(6 "In2.Cu" signal "VCC")
		(8 "In3.Cu" signal "VCC1")
		(10 "In4.Cu" signal "GND1")
		(12 "In5.Cu" signal "IN1")
		(14 "In6.Cu" signal "GND2")
		(16 "In7.Cu" signal "IN2")
		(18 "In8.Cu" signal "GND3")
		(20 "In9.Cu" signal "IN3")
		(22 "In10.Cu" signal "GND4")
		(24 "In11.Cu" signal "IN4")
		(26 "In12.Cu" signal "GND5")
		(28 "In13.Cu" signal "IN5")
		(30 "In14.Cu" signal "GND6")
		(32 "In15.Cu" signal "IN6")
		(34 "In16.Cu" signal "GND7")
		(2 "B.Cu" signal "BOTTOM")
		(9 "F.Adhes" user "F.Adhesive")
		(11 "B.Adhes" user "B.Adhesive")
		(13 "F.Paste" user "Package Geometry/Pastemask Top")
		(15 "B.Paste" user "Package Geometry/Pastemask Bottom")
		(5 "F.SilkS" user "Ref Des/Silkscreen Top")
		(7 "B.SilkS" user "Ref Des/Silkscreen Bottom")
		(1 "F.Mask" user "Board Geometry/Soldermask Top")
		(3 "B.Mask" user "Board Geometry/Soldermask Bottom")
		(17 "Dwgs.User" user "User.Drawings")
		(19 "Cmts.User" user "User.Comments")
		(21 "Eco1.User" user "User.Eco1")
		(23 "Eco2.User" user "User.Eco2")
		(25 "Edge.Cuts" user "Board Geometry/Outline")
		(27 "Margin" user)
		(31 "F.CrtYd" user "Package Geometry/Place Bound Top")
		(29 "B.CrtYd" user "Package Geometry/Place Bound Bottom")
		(35 "F.Fab" user "Ref Des/Assembly Top")
		(33 "B.Fab" user "Ref Des/Assembly Bottom")
	)
	(footprint ""
		(layer "F.Cu")
		(at 228.79304 -91.025726)
		(property "Reference" "R1014"
			(at 0 0 0)
			(layer "F.SilkS")
			(hide yes)
			(effects
				(font
					(size 1.27 1.27)
				)
			)
		)
		(property "Value" ""
			(at 0 0 0)
			(layer "F.Fab")
			(effects
				(font
					(size 1.27 1.27)
				)
			)
		)
		(duplicate_pad_numbers_are_jumpers no)
		(fp_line
			(start -0.7874 -0.4064)
			(end 0.7874 -0.4064)
			(stroke
				(width 0.1524)
				(type default)
			)
			(layer "F.SilkS")
		)
		(fp_line
			(start -0.7874 0.4064)
			(end -0.7874 -0.4064)
			(stroke
				(width 0.1524)
				(type default)
			)
			(layer "F.SilkS")
		)
		(fp_line
			(start 0.7874 -0.4064)
			(end 0.7874 0.4064)
			(stroke
				(width 0.1524)
				(type default)
			)
			(layer "F.SilkS")
		)
		(fp_line
			(start 0.7874 0.4064)
			(end -0.7874 0.4064)
			(stroke
				(width 0.1524)
				(type default)
			)
			(layer "F.SilkS")
		)
		(fp_line
			(start -0.67945 -0.305054)
			(end -0.12065 -0.305054)
			(stroke
				(width 0.1)
				(type default)
			)
			(layer "F.Fab")
		)
		(fp_line
			(start -0.67945 0.3048)
			(end -0.67945 -0.305054)
			(stroke
				(width 0.1)
				(type default)
			)
			(layer "F.Fab")
		)
		(fp_line
			(start -0.12065 -0.305054)
			(end -0.12065 -0.2794)
			(stroke
				(width 0.1)
				(type default)
			)
			(layer "F.Fab")
		)
		(fp_line
			(start -0.12065 -0.2794)
			(end 0.12065 -0.2794)
			(stroke
				(width 0.1)
				(type default)
			)
			(layer "F.Fab")
		)
		(fp_line
			(start -0.12065 0.2794)
			(end -0.12065 0.3048)
			(stroke
				(width 0.1)
				(type default)
			)
			(layer "F.Fab")
		)
		(fp_line
			(start -0.12065 0.3048)
			(end -0.67945 0.3048)
			(stroke
				(width 0.1)
				(type default)
			)
			(layer "F.Fab")
		)
		(fp_line
			(start 0.120396 0.2794)
			(end -0.12065 0.2794)
			(stroke
				(width 0.1)
				(type default)
			)
			(layer "F.Fab")
		)
		(fp_line
			(start 0.120396 0.3048)
			(end 0.120396 0.2794)
			(stroke
				(width 0.1)
				(type default)
			)
			(layer "F.Fab")
		)
		(fp_line
			(start 0.12065 -0.3048)
			(end 0.67945 -0.3048)
			(stroke
				(width 0.1)
				(type default)
			)
			(layer "F.Fab")
		)
		(fp_line
			(start 0.12065 -0.2794)
			(end 0.12065 -0.3048)
			(stroke
				(width 0.1)
				(type default)
			)
			(layer "F.Fab")
		)
		(fp_line
			(start 0.67945 -0.3048)
			(end 0.67945 0.3048)
			(stroke
				(width 0.1)
				(type default)
			)
			(layer "F.Fab")
		)
		(fp_line
			(start 0.67945 0.3048)
			(end 0.120396 0.3048)
			(stroke
				(width 0.1)
				(type default)
			)
			(layer "F.Fab")
		)
		(pad "1" smd circle
			(at -0.40005 0)
			(size 0 0)
			(layers "F.Cu" "F.Mask" "F.Paste")
			(net "P3V3_AUX")
		)
		(pad "2" smd circle
			(at 0.40005 0)
			(size 0 0)
			(layers "F.Cu" "F.Mask" "F.Paste")
			(net "PEX_USB_HUB_OVCUR2")
		)
	)
	(footprint ""
		(layer "F.Cu")
		(at 258.54533 -209.799174)
		(property "Reference" "C2811"
			(at 0 0 0)
			(layer "F.SilkS")
			(hide yes)
			(effects
				(font
					(size 1.27 1.27)
				)
			)
		)
		(property "Value" ""
			(at 0 0 0)
			(layer "F.Fab")
			(effects
				(font
					(size 1.27 1.27)
				)
			)
		)
		(duplicate_pad_numbers_are_jumpers no)
		(fp_line
			(start -0.7874 -0.4064)
			(end 0.7874 -0.4064)
			(stroke
				(width 0.1524)
				(type default)
			)
			(layer "F.SilkS")
		)
		(fp_line
			(start -0.7874 0.4064)
			(end -0.7874 -0.4064)
			(stroke
				(width 0.1524)
				(type default)
			)
			(layer "F.SilkS")
		)
		(fp_line
			(start 0.7874 -0.4064)
			(end 0.7874 0.4064)
			(stroke
				(width 0.1524)
				(type default)
			)
			(layer "F.SilkS")
		)
		(fp_line
			(start 0.7874 0.4064)
			(end -0.7874 0.4064)
			(stroke
				(width 0.1524)
				(type default)
			)
			(layer "F.SilkS")
		)
		(fp_line
			(start -0.67945 -0.305054)
			(end -0.12065 -0.305054)
			(stroke
				(width 0.1)
				(type default)
			)
			(layer "F.Fab")
		)
		(fp_line
			(start -0.67945 0.3048)
			(end -0.67945 -0.305054)
			(stroke
				(width 0.1)
				(type default)
			)
			(layer "F.Fab")
		)
		(fp_line
			(start -0.12065 -0.305054)
			(end -0.12065 -0.2794)
			(stroke
				(width 0.1)
				(type default)
			)
			(layer "F.Fab")
		)
		(fp_line
			(start -0.12065 -0.2794)
			(end 0.12065 -0.2794)
			(stroke
				(width 0.1)
				(type default)
			)
			(layer "F.Fab")
		)
		(fp_line
			(start -0.12065 0.2794)
			(end -0.12065 0.3048)
			(stroke
				(width 0.1)
				(type default)
			)
			(layer "F.Fab")
		)
		(fp_line
			(start -0.12065 0.3048)
			(end -0.67945 0.3048)
			(stroke
				(width 0.1)
				(type default)
			)
			(layer "F.Fab")
		)
		(fp_line
			(start 0.120396 0.2794)
			(end -0.12065 0.2794)
			(stroke
				(width 0.1)
				(type default)
			)
			(layer "F.Fab")
		)
		(fp_line
			(start 0.120396 0.3048)
			(end 0.120396 0.2794)
			(stroke
				(width 0.1)
				(type default)
			)
			(layer "F.Fab")
		)
		(fp_line
			(start 0.12065 -0.3048)
			(end 0.67945 -0.3048)
			(stroke
				(width 0.1)
				(type default)
			)
			(layer "F.Fab")
		)
		(fp_line
			(start 0.12065 -0.2794)
			(end 0.12065 -0.3048)
			(stroke
				(width 0.1)
				(type default)
			)
			(layer "F.Fab")
		)
		(fp_line
			(start 0.67945 -0.3048)
			(end 0.67945 0.3048)
			(stroke
				(width 0.1)
				(type default)
			)
			(layer "F.Fab")
		)
		(fp_line
			(start 0.67945 0.3048)
			(end 0.120396 0.3048)
			(stroke
				(width 0.1)
				(type default)
			)
			(layer "F.Fab")
		)
		(pad "1" smd circle
			(at -0.40005 0)
			(size 0 0)
			(layers "F.Cu" "F.Mask" "F.Paste")
			(net "GND")
		)
		(pad "2" smd circle
			(at 0.40005 0)
			(size 0 0)
			(layers "F.Cu" "F.Mask" "F.Paste")
			(net "P3V3_AUX_JTAG")
		)
	)
	(footprint ""
		(layer "F.Cu")
		(at 31.742888 -356.244906 90)
		(property "Reference" "C2164"
			(at 0 0 90)
			(layer "F.SilkS")
			(hide yes)
			(effects
				(font
					(size 1.27 1.27)
				)
			)
		)
		(property "Value" ""
			(at 0 0 90)
			(layer "F.Fab")
			(effects
				(font
					(size 1.27 1.27)
				)
			)
		)
		(duplicate_pad_numbers_are_jumpers no)
		(fp_line
			(start 0.299974 -0.150114)
			(end 0.299974 0.150114)
			(stroke
				(width 0.1)
				(type default)
			)
			(layer "F.Fab")
		)
		(fp_line
			(start -0.299974 -0.150114)
			(end 0.299974 -0.150114)
			(stroke
				(width 0.1)
				(type default)
			)
			(layer "F.Fab")
		)
		(fp_line
			(start 0.299974 0.150114)
			(end -0.299974 0.150114)
			(stroke
				(width 0.1)
				(type default)
			)
			(layer "F.Fab")
		)
		(fp_line
			(start -0.299974 0.150114)
			(end -0.299974 -0.150114)
			(stroke
				(width 0.1)
				(type default)
			)
			(layer "F.Fab")
		)
		(pad "1" smd rect
			(at -0.2667 0 90)
			(size 0.3048 0.381)
			(layers "F.Cu" "F.Mask" "F.Paste")
			(net "P5E_PEX0_STN4_TX_DP<73>")
		)
		(pad "2" smd rect
			(at 0.2667 0 90)
			(size 0.3048 0.381)
			(layers "F.Cu" "F.Mask" "F.Paste")
			(net "P5E_PEX0_STN4_TX_C_DP<73>")
		)
	)
	(footprint ""
		(layer "F.Cu")
		(at 338.263484 -356.244906 90)
		(property "Reference" "C576"
			(at 0 0 90)
			(layer "F.SilkS")
			(hide yes)
			(effects
				(font
					(size 1.27 1.27)
				)
			)
		)
		(property "Value" ""
			(at 0 0 90)
			(layer "F.Fab")
			(effects
				(font
					(size 1.27 1.27)
				)
			)
		)
		(duplicate_pad_numbers_are_jumpers no)
		(fp_line
			(start 0.299974 -0.150114)
			(end 0.299974 0.150114)
			(stroke
				(width 0.1)
				(type default)
			)
			(layer "F.Fab")
		)
		(fp_line
			(start -0.299974 -0.150114)
			(end 0.299974 -0.150114)
			(stroke
				(width 0.1)
				(type default)
			)
			(layer "F.Fab")
		)
		(fp_line
			(start 0.299974 0.150114)
			(end -0.299974 0.150114)
			(stroke
				(width 0.1)
				(type default)
			)
			(layer "F.Fab")
		)
		(fp_line
			(start -0.299974 0.150114)
			(end -0.299974 -0.150114)
			(stroke
				(width 0.1)
				(type default)
			)
			(layer "F.Fab")
		)
		(pad "1" smd rect
			(at -0.2667 0 90)
			(size 0.3048 0.381)
			(layers "F.Cu" "F.Mask" "F.Paste")
			(net "P5E_PEX2_STN6_TX_DN<99>")
		)
		(pad "2" smd rect
			(at 0.2667 0 90)
			(size 0.3048 0.381)
			(layers "F.Cu" "F.Mask" "F.Paste")
			(net "P5E_PEX2_STN6_TX_C_DN<99>")
		)
	)
	(footprint ""
		(layer "F.Cu")
		(at 146.255486 -390.398254 90)
		(property "Reference" "R1847"
			(at 0 0 90)
			(layer "F.SilkS")
			(hide yes)
			(effects
				(font
					(size 1.27 1.27)
				)
			)
		)
		(property "Value" ""
			(at 0 0 90)
			(layer "F.Fab")
			(effects
				(font
					(size 1.27 1.27)
				)
			)
		)
		(duplicate_pad_numbers_are_jumpers no)
		(fp_line
			(start 0.7874 -0.4064)
			(end 0.7874 0.4064)
			(stroke
				(width 0.1524)
				(type default)
			)
			(layer "F.SilkS")
		)
		(fp_line
			(start -0.7874 -0.4064)
			(end 0.7874 -0.4064)
			(stroke
				(width 0.1524)
				(type default)
			)
			(layer "F.SilkS")
		)
		(fp_line
			(start 0.7874 0.4064)
			(end -0.7874 0.4064)
			(stroke
				(width 0.1524)
				(type default)
			)
			(layer "F.SilkS")
		)
		(fp_line
			(start -0.7874 0.4064)
			(end -0.7874 -0.4064)
			(stroke
				(width 0.1524)
				(type default)
			)
			(layer "F.SilkS")
		)
		(fp_line
			(start -0.12065 -0.305054)
			(end -0.12065 -0.2794)
			(stroke
				(width 0.1)
				(type default)
			)
			(layer "F.Fab")
		)
		(fp_line
			(start -0.67945 -0.305054)
			(end -0.12065 -0.305054)
			(stroke
				(width 0.1)
				(type default)
			)
			(layer "F.Fab")
		)
		(fp_line
			(start 0.67945 -0.3048)
			(end 0.67945 0.3048)
			(stroke
				(width 0.1)
				(type default)
			)
			(layer "F.Fab")
		)
		(fp_line
			(start 0.12065 -0.3048)
			(end 0.67945 -0.3048)
			(stroke
				(width 0.1)
				(type default)
			)
			(layer "F.Fab")
		)
		(fp_line
			(start 0.12065 -0.2794)
			(end 0.12065 -0.3048)
			(stroke
				(width 0.1)
				(type default)
			)
			(layer "F.Fab")
		)
		(fp_line
			(start -0.12065 -0.2794)
			(end 0.12065 -0.2794)
			(stroke
				(width 0.1)
				(type default)
			)
			(layer "F.Fab")
		)
		(fp_line
			(start 0.120396 0.2794)
			(end -0.12065 0.2794)
			(stroke
				(width 0.1)
				(type default)
			)
			(layer "F.Fab")
		)
		(fp_line
			(start -0.12065 0.2794)
			(end -0.12065 0.3048)
			(stroke
				(width 0.1)
				(type default)
			)
			(layer "F.Fab")
		)
		(fp_line
			(start 0.67945 0.3048)
			(end 0.120396 0.3048)
			(stroke
				(width 0.1)
				(type default)
			)
			(layer "F.Fab")
		)
		(fp_line
			(start 0.120396 0.3048)
			(end 0.120396 0.2794)
			(stroke
				(width 0.1)
				(type default)
			)
			(layer "F.Fab")
		)
		(fp_line
			(start -0.12065 0.3048)
			(end -0.67945 0.3048)
			(stroke
				(width 0.1)
				(type default)
			)
			(layer "F.Fab")
		)
		(fp_line
			(start -0.67945 0.3048)
			(end -0.67945 -0.305054)
			(stroke
				(width 0.1)
				(type default)
			)
			(layer "F.Fab")
		)
		(pad "1" smd circle
			(at -0.40005 0 90)
			(size 0 0)
			(layers "F.Cu" "F.Mask" "F.Paste")
			(net "GPU_FPGA_BOOT_EN_R")
		)
		(pad "2" smd circle
			(at 0.40005 0 90)
			(size 0 0)
			(layers "F.Cu" "F.Mask" "F.Paste")
			(net "GPU_FPGA_BOOT_EN")
		)
	)
	(footprint ""
		(layer "F.Cu")
		(at 251.56287 -79.379318 -90)
		(property "Reference" "C2636"
			(at 0 0 270)
			(layer "F.SilkS")
			(hide yes)
			(effects
				(font
					(size 1.27 1.27)
				)
			)
		)
		(property "Value" ""
			(at 0 0 270)
			(layer "F.Fab")
			(effects
				(font
					(size 1.27 1.27)
				)
			)
		)
		(duplicate_pad_numbers_are_jumpers no)
		(fp_line
			(start -0.7874 0.4064)
			(end -0.7874 -0.4064)
			(stroke
				(width 0.1524)
				(type default)
			)
			(layer "F.SilkS")
		)
		(fp_line
			(start 0.7874 0.4064)
			(end -0.7874 0.4064)
			(stroke
				(width 0.1524)
				(type default)
			)
			(layer "F.SilkS")
		)
		(fp_line
			(start -0.7874 -0.4064)
			(end 0.7874 -0.4064)
			(stroke
				(width 0.1524)
				(type default)
			)
			(layer "F.SilkS")
		)
		(fp_line
			(start 0.7874 -0.4064)
			(end 0.7874 0.4064)
			(stroke
				(width 0.1524)
				(type default)
			)
			(layer "F.SilkS")
		)
		(fp_line
			(start -0.67945 0.3048)
			(end -0.67945 -0.305054)
			(stroke
				(width 0.1)
				(type default)
			)
			(layer "F.Fab")
		)
		(fp_line
			(start -0.12065 0.3048)
			(end -0.67945 0.3048)
			(stroke
				(width 0.1)
				(type default)
			)
			(layer "F.Fab")
		)
		(fp_line
			(start 0.120396 0.3048)
			(end 0.120396 0.2794)
			(stroke
				(width 0.1)
				(type default)
			)
			(layer "F.Fab")
		)
		(fp_line
			(start 0.67945 0.3048)
			(end 0.120396 0.3048)
			(stroke
				(width 0.1)
				(type default)
			)
			(layer "F.Fab")
		)
		(fp_line
			(start -0.12065 0.2794)
			(end -0.12065 0.3048)
			(stroke
				(width 0.1)
				(type default)
			)
			(layer "F.Fab")
		)
		(fp_line
			(start 0.120396 0.2794)
			(end -0.12065 0.2794)
			(stroke
				(width 0.1)
				(type default)
			)
			(layer "F.Fab")
		)
		(fp_line
			(start -0.12065 -0.2794)
			(end 0.12065 -0.2794)
			(stroke
				(width 0.1)
				(type default)
			)
			(layer "F.Fab")
		)
		(fp_line
			(start 0.12065 -0.2794)
			(end 0.12065 -0.3048)
			(stroke
				(width 0.1)
				(type default)
			)
			(layer "F.Fab")
		)
		(fp_line
			(start 0.12065 -0.3048)
			(end 0.67945 -0.3048)
			(stroke
				(width 0.1)
				(type default)
			)
			(layer "F.Fab")
		)
		(fp_line
			(start 0.67945 -0.3048)
			(end 0.67945 0.3048)
			(stroke
				(width 0.1)
				(type default)
			)
			(layer "F.Fab")
		)
		(fp_line
			(start -0.67945 -0.305054)
			(end -0.12065 -0.305054)
			(stroke
				(width 0.1)
				(type default)
			)
			(layer "F.Fab")
		)
		(fp_line
			(start -0.12065 -0.305054)
			(end -0.12065 -0.2794)
			(stroke
				(width 0.1)
				(type default)
			)
			(layer "F.Fab")
		)
		(pad "1" smd circle
			(at -0.40005 0 270)
			(size 0 0)
			(layers "F.Cu" "F.Mask" "F.Paste")
			(net "XTAL_CK440_25M_R_XIN")
		)
		(pad "2" smd circle
			(at 0.40005 0 270)
			(size 0 0)
			(layers "F.Cu" "F.Mask" "F.Paste")
			(net "GND")
		)
	)
	(footprint ""
		(layer "F.Cu")
		(at 289.14725 -36.686998 90)
		(property "Reference" "C3676"
			(at 0 0 90)
			(layer "F.SilkS")
			(hide yes)
			(effects
				(font
					(size 1.27 1.27)
				)
			)
		)
		(property "Value" ""
			(at 0 0 90)
			(layer "F.Fab")
			(effects
				(font
					(size 1.27 1.27)
				)
			)
		)
		(duplicate_pad_numbers_are_jumpers no)
		(fp_line
			(start 0.7874 -0.4064)
			(end 0.7874 0.4064)
			(stroke
				(width 0.1524)
				(type default)
			)
			(layer "F.SilkS")
		)
		(fp_line
			(start -0.7874 -0.4064)
			(end 0.7874 -0.4064)
			(stroke
				(width 0.1524)
				(type default)
			)
			(layer "F.SilkS")
		)
		(fp_line
			(start 0.7874 0.4064)
			(end -0.7874 0.4064)
			(stroke
				(width 0.1524)
				(type default)
			)
			(layer "F.SilkS")
		)
		(fp_line
			(start -0.7874 0.4064)
			(end -0.7874 -0.4064)
			(stroke
				(width 0.1524)
				(type default)
			)
			(layer "F.SilkS")
		)
		(fp_line
			(start -0.12065 -0.305054)
			(end -0.12065 -0.2794)
			(stroke
				(width 0.1)
				(type default)
			)
			(layer "F.Fab")
		)
		(fp_line
			(start -0.67945 -0.305054)
			(end -0.12065 -0.305054)
			(stroke
				(width 0.1)
				(type default)
			)
			(layer "F.Fab")
		)
		(fp_line
			(start 0.67945 -0.3048)
			(end 0.67945 0.3048)
			(stroke
				(width 0.1)
				(type default)
			)
			(layer "F.Fab")
		)
		(fp_line
			(start 0.12065 -0.3048)
			(end 0.67945 -0.3048)
			(stroke
				(width 0.1)
				(type default)
			)
			(layer "F.Fab")
		)
		(fp_line
			(start 0.12065 -0.2794)
			(end 0.12065 -0.3048)
			(stroke
				(width 0.1)
				(type default)
			)
			(layer "F.Fab")
		)
		(fp_line
			(start -0.12065 -0.2794)
			(end 0.12065 -0.2794)
			(stroke
				(width 0.1)
				(type default)
			)
			(layer "F.Fab")
		)
		(fp_line
			(start 0.120396 0.2794)
			(end -0.12065 0.2794)
			(stroke
				(width 0.1)
				(type default)
			)
			(layer "F.Fab")
		)
		(fp_line
			(start -0.12065 0.2794)
			(end -0.12065 0.3048)
			(stroke
				(width 0.1)
				(type default)
			)
			(layer "F.Fab")
		)
		(fp_line
			(start 0.67945 0.3048)
			(end 0.120396 0.3048)
			(stroke
				(width 0.1)
				(type default)
			)
			(layer "F.Fab")
		)
		(fp_line
			(start 0.120396 0.3048)
			(end 0.120396 0.2794)
			(stroke
				(width 0.1)
				(type default)
			)
			(layer "F.Fab")
		)
		(fp_line
			(start -0.12065 0.3048)
			(end -0.67945 0.3048)
			(stroke
				(width 0.1)
				(type default)
			)
			(layer "F.Fab")
		)
		(fp_line
			(start -0.67945 0.3048)
			(end -0.67945 -0.305054)
			(stroke
				(width 0.1)
				(type default)
			)
			(layer "F.Fab")
		)
		(pad "1" smd circle
			(at -0.40005 0 90)
			(size 0 0)
			(layers "F.Cu" "F.Mask" "F.Paste")
			(net "P3V3_AUX")
		)
		(pad "2" smd circle
			(at 0.40005 0 90)
			(size 0 0)
			(layers "F.Cu" "F.Mask" "F.Paste")
			(net "GND")
		)
	)
)
